(kicad_pcb
	(version 20260206)
	(generator "pcbnew")
	(generator_version "10.0")
	(general
		(thickness 1.6)
		(legacy_teardrops no)
	)
	(paper "A4")
	(title_block
		(title "timecard-production-celestica-r4006 — R4006-B0001-02_R01.brd")
		(comment 1 "Time Appliance Project (Time Card) / footprints 607-611 of 1113")
	)
	(layers
		(0 "F.Cu" signal "TOP")
		(4 "In1.Cu" signal "L02_GND1")
		(6 "In2.Cu" signal "L03_SIG1")
		(8 "In3.Cu" signal "L04_GND2")
		(10 "In4.Cu" signal "L05_VCC1")
		(12 "In5.Cu" signal "L06_VCC2")
		(14 "In6.Cu" signal "L07_GND3")
		(16 "In7.Cu" signal "L08_SIG2")
		(18 "In8.Cu" signal "L09_GND4")
		(2 "B.Cu" signal "BOTTOM")
		(9 "F.Adhes" user "F.Adhesive")
		(11 "B.Adhes" user "B.Adhesive")
		(13 "F.Paste" user "Package Geometry/Pastemask Top")
		(15 "B.Paste" user "Package Geometry/Pastemask Bottom")
		(5 "F.SilkS" user "Ref Des/Silkscreen Top")
		(7 "B.SilkS" user "Ref Des/Silkscreen Bottom")
		(1 "F.Mask" user "Board Geometry/Soldermask Top")
		(3 "B.Mask" user "Board Geometry/Soldermask Bottom")
		(17 "Dwgs.User" user "User.Drawings")
		(19 "Cmts.User" user "User.Comments")
		(21 "Eco1.User" user "User.Eco1")
		(23 "Eco2.User" user "User.Eco2")
		(25 "Edge.Cuts" user "Board Geometry/Outline")
		(27 "Margin" user)
		(31 "F.CrtYd" user "Package Geometry/Place Bound Top")
		(29 "B.CrtYd" user "Package Geometry/Place Bound Bottom")
		(35 "F.Fab" user "Ref Des/Assembly Top")
		(33 "B.Fab" user "Ref Des/Assembly Bottom")
	)
	(footprint ""
		(layer "F.Cu")
		(at 88.6714 -64.4144 90)
		(property "Reference" "L19"
			(at 12.8016 -10.01903 90)
			(unlocked yes)
			(layer "F.SilkS")
			(effects
				(font
					(size 0.7874 0.5842)
					(thickness 0.1524)
				)
			)
		)
		(property "Value" "VAL*"
			(at 0.014732 2.526538 90)
			(unlocked yes)
			(layer "F.Fab")
			(hide yes)
			(effects
				(font
					(size 0.7874 0.5842)
					(thickness 0.000001)
				)
			)
		)
		(property "Tolerance" "TOL*"
			(at 0.014732 3.503676 90)
			(unlocked yes)
			(layer "Cmts.User")
			(hide yes)
			(effects
				(font
					(size 0.7874 0.5842)
					(thickness 0.000001)
				)
			)
		)
		(property "User Part Number" "PARTNUM*"
			(at 0.02794 4.480814 90)
			(unlocked yes)
			(layer "Cmts.User")
			(hide yes)
			(effects
				(font
					(size 0.7874 0.5842)
					(thickness 0.000001)
				)
			)
		)
		(property "Device Type" "FERRITEBEAD-G191-10097-01,600OA"
			(at 0.014732 1.600708 90)
			(unlocked yes)
			(layer "F.Fab")
			(hide yes)
			(effects
				(font
					(size 0.7874 0.5842)
					(thickness 0.000001)
				)
			)
		)
		(duplicate_pad_numbers_are_jumpers no)
		(fp_line
			(start 1.3208 -0.7112)
			(end 1.3208 0.7112)
			(stroke
				(width 0.1)
				(type default)
			)
			(layer "F.SilkS")
		)
		(fp_line
			(start -1.3208 -0.7112)
			(end 1.3208 -0.7112)
			(stroke
				(width 0.1)
				(type default)
			)
			(layer "F.SilkS")
		)
		(fp_line
			(start 1.3208 0.7112)
			(end -1.3208 0.7112)
			(stroke
				(width 0.1)
				(type default)
			)
			(layer "F.SilkS")
		)
		(fp_line
			(start -1.3208 0.7112)
			(end -1.3208 -0.7112)
			(stroke
				(width 0.1)
				(type default)
			)
			(layer "F.SilkS")
		)
		(fp_rect
			(start -1.3208 0.7112)
			(end 1.3208 -0.7112)
			(stroke
				(width 0)
				(type default)
			)
			(fill no)
			(layer "F.CrtYd")
		)
		(fp_line
			(start 0.8128 -0.4572)
			(end 0.8128 0.4572)
			(stroke
				(width 0.1)
				(type default)
			)
			(layer "F.Fab")
		)
		(fp_line
			(start -0.8128 -0.4572)
			(end 0.8128 -0.4572)
			(stroke
				(width 0.1)
				(type default)
			)
			(layer "F.Fab")
		)
		(fp_line
			(start 0.8128 0.4572)
			(end -0.8128 0.4572)
			(stroke
				(width 0.1)
				(type default)
			)
			(layer "F.Fab")
		)
		(fp_line
			(start -0.8128 0.4572)
			(end -0.8128 -0.4572)
			(stroke
				(width 0.1)
				(type default)
			)
			(layer "F.Fab")
		)
		(pad "1" smd rect
			(at -0.6858 0 90)
			(size 0.762 0.8636)
			(layers "F.Cu" "F.Mask" "F.Paste")
			(net "VDD_BNO085")
		)
		(pad "2" smd rect
			(at 0.6858 0 90)
			(size 0.762 0.8636)
			(layers "F.Cu" "F.Mask" "F.Paste")
			(net "XP3R3V_FPGA")
		)
		(zone
			(layer "F.Cu")
			(hatch none 0.5)
			(connect_pads
				(clearance 0)
			)
			(min_thickness 0.25)
			(keepout
				(tracks allowed)
				(vias not_allowed)
				(pads allowed)
				(copperpour not_allowed)
				(footprints allowed)
			)
			(placement
				(enabled no)
				(sheetname "")
			)
			(fill
				(thermal_gap 0.5)
				(thermal_bridge_width 0.5)
				(island_removal_mode 0)
			)
			(polygon
				(pts
					(xy 89.1286 -64.262) (xy 89.1286 -64.5668) (xy 88.2142 -64.5668) (xy 88.2142 -64.262)
				)
			)
		)
		(zone
			(layer "F.Cu")
			(hatch none 0.5)
			(connect_pads
				(clearance 0)
			)
			(min_thickness 0.25)
			(keepout
				(tracks not_allowed)
				(vias allowed)
				(pads allowed)
				(copperpour not_allowed)
				(footprints allowed)
			)
			(placement
				(enabled no)
				(sheetname "")
			)
			(fill
				(thermal_gap 0.5)
				(thermal_bridge_width 0.5)
				(island_removal_mode 0)
			)
			(polygon
				(pts
					(xy 89.1286 -64.262) (xy 89.1286 -64.5668) (xy 88.2142 -64.5668) (xy 88.2142 -64.262)
				)
			)
		)
	)
	(footprint ""
		(layer "F.Cu")
		(at 153.049986 -104.350058 -90)
		(property "Reference" "DS20"
			(at 1.099058 -1.548384 90)
			(unlocked yes)
			(layer "F.SilkS")
			(effects
				(font
					(size 0.7874 0.5842)
					(thickness 0.1524)
				)
			)
		)
		(property "Value" ""
			(at 0 0 270)
			(layer "F.Fab")
			(effects
				(font
					(size 1.27 1.27)
				)
			)
		)
		(property "Device Type" "OPTICAL-G170-10143-01"
			(at 0.1778 1.483081 270)
			(unlocked yes)
			(layer "F.Fab")
			(hide yes)
			(effects
				(font
					(size 0.786892 0.583946)
					(thickness 0.000001)
				)
			)
		)
		(property "User Part Number" "PARTNUM*"
			(at 0.1778 2.422881 270)
			(unlocked yes)
			(layer "Cmts.User")
			(hide yes)
			(effects
				(font
					(size 0.786892 0.583946)
					(thickness 0.000001)
				)
			)
		)
		(duplicate_pad_numbers_are_jumpers no)
		(fp_line
			(start -1.1938 1.7272)
			(end -2.4638 1.7272)
			(stroke
				(width 0.1)
				(type default)
			)
			(layer "F.SilkS")
		)
		(fp_line
			(start -1.8288 1.0922)
			(end -1.8288 2.3622)
			(stroke
				(width 0.1)
				(type default)
			)
			(layer "F.SilkS")
		)
		(fp_line
			(start -1.397508 0.704088)
			(end -1.397508 -0.704088)
			(stroke
				(width 0.1)
				(type default)
			)
			(layer "F.SilkS")
		)
		(fp_line
			(start 1.397508 0.704088)
			(end -1.397508 0.704088)
			(stroke
				(width 0.1)
				(type default)
			)
			(layer "F.SilkS")
		)
		(fp_line
			(start -1.397508 -0.704088)
			(end 1.397508 -0.704088)
			(stroke
				(width 0.1)
				(type default)
			)
			(layer "F.SilkS")
		)
		(fp_line
			(start 1.397508 -0.704088)
			(end 1.397508 0.704088)
			(stroke
				(width 0.1)
				(type default)
			)
			(layer "F.SilkS")
		)
		(fp_poly
			(pts
				(xy 1.397508 0.704088) (xy 1.397508 -0.704088) (xy 1.905508 -0.704088) (xy 1.905508 0.704088)
			)
			(stroke
				(width 0)
				(type default)
			)
			(fill yes)
			(layer "F.SilkS")
		)
		(fp_poly
			(pts
				(xy -1.651508 0.958088) (xy 1.905508 0.958088) (xy 1.905508 -0.958088) (xy -1.651508 -0.958088)
			)
			(stroke
				(width 0)
				(type default)
			)
			(fill no)
			(layer "F.CrtYd")
		)
		(fp_line
			(start -1.4478 1.3462)
			(end -2.7178 1.3462)
			(stroke
				(width 0.1)
				(type default)
			)
			(layer "F.Fab")
		)
		(fp_line
			(start -2.0828 0.7112)
			(end -2.0828 1.9812)
			(stroke
				(width 0.1)
				(type default)
			)
			(layer "F.Fab")
		)
		(fp_line
			(start -0.850138 0.450088)
			(end 0.850138 0.450088)
			(stroke
				(width 0.1)
				(type default)
			)
			(layer "F.Fab")
		)
		(fp_line
			(start 0.850138 0.450088)
			(end 0.850138 -0.450088)
			(stroke
				(width 0.1)
				(type default)
			)
			(layer "F.Fab")
		)
		(fp_line
			(start -0.850138 -0.450088)
			(end -0.850138 0.450088)
			(stroke
				(width 0.1)
				(type default)
			)
			(layer "F.Fab")
		)
		(fp_line
			(start 0.850138 -0.450088)
			(end -0.850138 -0.450088)
			(stroke
				(width 0.1)
				(type default)
			)
			(layer "F.Fab")
		)
		(fp_poly
			(pts
				(xy 0.850138 -0.450088) (xy 0.850138 0.450088) (xy 0.342138 0.450088) (xy 0.342138 -0.450088)
			)
			(stroke
				(width 0)
				(type default)
			)
			(fill yes)
			(layer "F.Fab")
		)
		(fp_text user "C"
			(at 2.527808 0.268986 0)
			(unlocked yes)
			(layer "F.SilkS")
			(effects
				(font
					(size 0.635 0.4064)
					(thickness 0.1524)
				)
			)
		)
		(fp_text user "A"
			(at -1.028192 -1.255014 0)
			(unlocked yes)
			(layer "F.SilkS")
			(effects
				(font
					(size 0.635 0.4064)
					(thickness 0.1524)
				)
			)
		)
		(fp_text user "A"
			(at -1.020572 1.030986 0)
			(unlocked yes)
			(layer "F.Fab")
			(effects
				(font
					(size 0.7874 0.5842)
					(thickness 0.1524)
				)
			)
		)
		(fp_text user "C"
			(at 2.281428 -0.112014 0)
			(unlocked yes)
			(layer "F.Fab")
			(effects
				(font
					(size 0.7874 0.5842)
					(thickness 0.1524)
				)
			)
		)
		(pad "A" smd rect
			(at -0.749808 0 270)
			(size 0.7874 0.7874)
			(layers "F.Cu" "F.Mask" "F.Paste")
			(net "UNNAMED_14_OPTICAL_I194_A")
		)
		(pad "C" smd rect
			(at 0.749808 0 270)
			(size 0.7874 0.7874)
			(layers "F.Cu" "F.Mask" "F.Paste")
			(net "SG")
		)
	)
	(footprint ""
		(layer "F.Cu")
		(at 139.329922 -100.7618 180)
		(property "Reference" "R12"
			(at 1.153922 1.05283 0)
			(unlocked yes)
			(layer "F.SilkS")
			(effects
				(font
					(size 0.7874 0.5842)
					(thickness 0.1524)
				)
			)
		)
		(property "Value" "VAL*"
			(at 0.02032 2.13233 180)
			(unlocked yes)
			(layer "F.Fab")
			(hide yes)
			(effects
				(font
					(size 0.7874 0.5842)
					(thickness 0.1524)
				)
			)
		)
		(property "Device Type" "RESISTOR-G155-11002-01,10KOHM,A"
			(at 0.008382 1.210564 180)
			(unlocked yes)
			(layer "F.Fab")
			(hide yes)
			(effects
				(font
					(size 0.7874 0.5842)
					(thickness 0.1524)
				)
			)
		)
		(property "User Part Number" "PARTNUM*"
			(at 0.02032 4.024884 180)
			(unlocked yes)
			(layer "Cmts.User")
			(hide yes)
			(effects
				(font
					(size 0.7874 0.5842)
					(thickness 0.1524)
				)
			)
		)
		(property "Tolerance" "TOL*"
			(at 0.044704 3.05435 180)
			(unlocked yes)
			(layer "Cmts.User")
			(hide yes)
			(effects
				(font
					(size 0.7874 0.5842)
					(thickness 0.1524)
				)
			)
		)
		(duplicate_pad_numbers_are_jumpers no)
		(fp_line
			(start 1.143 0.5588)
			(end 1.143 -0.5588)
			(stroke
				(width 0.1)
				(type default)
			)
			(layer "F.SilkS")
		)
		(fp_line
			(start 1.143 -0.5588)
			(end -1.143 -0.5588)
			(stroke
				(width 0.1)
				(type default)
			)
			(layer "F.SilkS")
		)
		(fp_line
			(start -1.143 0.5588)
			(end 1.143 0.5588)
			(stroke
				(width 0.1)
				(type default)
			)
			(layer "F.SilkS")
		)
		(fp_line
			(start -1.143 -0.5588)
			(end -1.143 0.5588)
			(stroke
				(width 0.1)
				(type default)
			)
			(layer "F.SilkS")
		)
		(fp_rect
			(start -1.143 0.5588)
			(end 1.143 -0.5588)
			(stroke
				(width 0)
				(type default)
			)
			(fill no)
			(layer "F.CrtYd")
		)
		(fp_line
			(start 0.508 0.3048)
			(end 0.508 -0.3048)
			(stroke
				(width 0.1)
				(type default)
			)
			(layer "F.Fab")
		)
		(fp_line
			(start 0.508 -0.3048)
			(end -0.508 -0.3048)
			(stroke
				(width 0.1)
				(type default)
			)
			(layer "F.Fab")
		)
		(fp_line
			(start -0.508 0.3048)
			(end 0.508 0.3048)
			(stroke
				(width 0.1)
				(type default)
			)
			(layer "F.Fab")
		)
		(fp_line
			(start -0.508 -0.3048)
			(end -0.508 0.3048)
			(stroke
				(width 0.1)
				(type default)
			)
			(layer "F.Fab")
		)
		(pad "1" smd rect
			(at -0.5334 0 180)
			(size 0.7112 0.6096)
			(layers "F.Cu" "F.Mask" "F.Paste")
			(net "XP12R0V_A_OV")
		)
		(pad "2" smd rect
			(at 0.5334 0 180)
			(size 0.7112 0.6096)
			(layers "F.Cu" "F.Mask" "F.Paste")
			(net "SG")
		)
		(zone
			(layer "F.Cu")
			(hatch none 0.5)
			(connect_pads
				(clearance 0)
			)
			(min_thickness 0.25)
			(keepout
				(tracks allowed)
				(vias not_allowed)
				(pads allowed)
				(copperpour not_allowed)
				(footprints allowed)
			)
			(placement
				(enabled no)
				(sheetname "")
			)
			(fill
				(thermal_gap 0.5)
				(thermal_bridge_width 0.5)
				(island_removal_mode 0)
			)
			(polygon
				(pts
					(xy 139.406122 -101.0666) (xy 139.253722 -101.0666) (xy 139.253722 -100.457) (xy 139.406122 -100.457)
				)
			)
		)
	)
	(footprint ""
		(layer "F.Cu")
		(at 89.8398 -104.6734 180)
		(property "Reference" "C77"
			(at -1.7272 0.69723 0)
			(unlocked yes)
			(layer "F.SilkS")
			(effects
				(font
					(size 0.7874 0.5842)
					(thickness 0.1524)
				)
			)
		)
		(property "Value" "VAL*"
			(at 0.193548 2.13614 180)
			(unlocked yes)
			(layer "F.Fab")
			(hide yes)
			(effects
				(font
					(size 0.7874 0.5842)
					(thickness 0.1524)
				)
			)
		)
		(property "User Part Number" "PARTNUM*"
			(at 0.216154 4.185666 180)
			(unlocked yes)
			(layer "Cmts.User")
			(hide yes)
			(effects
				(font
					(size 0.7874 0.5842)
					(thickness 0.1524)
				)
			)
		)
		(property "Device Type" "CAPACITOR-G104-0B103-EK,0.01UFA"
			(at 0.184404 1.180592 180)
			(unlocked yes)
			(layer "F.Fab")
			(hide yes)
			(effects
				(font
					(size 0.7874 0.5842)
					(thickness 0.1524)
				)
			)
		)
		(property "Tolerance" "TOL*"
			(at 0.216154 3.1496 180)
			(unlocked yes)
			(layer "Cmts.User")
			(hide yes)
			(effects
				(font
					(size 0.7874 0.5842)
					(thickness 0.1524)
				)
			)
		)
		(duplicate_pad_numbers_are_jumpers no)
		(fp_line
			(start 0.671322 0.4445)
			(end -0.671322 0.4445)
			(stroke
				(width 0.1)
				(type default)
			)
			(layer "F.SilkS")
		)
		(fp_line
			(start 0.671322 -0.4445)
			(end 0.671322 0.4445)
			(stroke
				(width 0.1)
				(type default)
			)
			(layer "F.SilkS")
		)
		(fp_line
			(start -0.671322 0.4445)
			(end -0.671322 -0.4445)
			(stroke
				(width 0.1)
				(type default)
			)
			(layer "F.SilkS")
		)
		(fp_line
			(start -0.671322 -0.4445)
			(end 0.671322 -0.4445)
			(stroke
				(width 0.1)
				(type default)
			)
			(layer "F.SilkS")
		)
		(fp_rect
			(start 0.671322 -0.4445)
			(end -0.671322 0.4445)
			(stroke
				(width 0)
				(type default)
			)
			(fill no)
			(layer "F.CrtYd")
		)
		(fp_line
			(start 0.31496 0.1651)
			(end 0.31496 -0.1651)
			(stroke
				(width 0.1)
				(type default)
			)
			(layer "F.Fab")
		)
		(fp_line
			(start 0.31496 -0.1651)
			(end -0.31496 -0.1651)
			(stroke
				(width 0.1)
				(type default)
			)
			(layer "F.Fab")
		)
		(fp_line
			(start -0.31496 0.1651)
			(end 0.31496 0.1651)
			(stroke
				(width 0.1)
				(type default)
			)
			(layer "F.Fab")
		)
		(fp_line
			(start -0.31496 -0.1651)
			(end -0.31496 0.1651)
			(stroke
				(width 0.1)
				(type default)
			)
			(layer "F.Fab")
		)
		(pad "1" smd rect
			(at -0.264922 0 180)
			(size 0.3048 0.381)
			(layers "F.Cu" "F.Mask" "F.Paste")
			(net "SG")
		)
		(pad "2" smd rect
			(at 0.264922 0 180)
			(size 0.3048 0.381)
			(layers "F.Cu" "F.Mask" "F.Paste")
			(net "R_XP3R3V_PG")
		)
		(zone
			(layer "F.Cu")
			(hatch none 0.5)
			(connect_pads
				(clearance 0)
			)
			(min_thickness 0.25)
			(keepout
				(tracks allowed)
				(vias not_allowed)
				(pads allowed)
				(copperpour not_allowed)
				(footprints allowed)
			)
			(placement
				(enabled no)
				(sheetname "")
			)
			(fill
				(thermal_gap 0.5)
				(thermal_bridge_width 0.5)
				(island_removal_mode 0)
			)
			(polygon
				(pts
					(xy 89.727278 -104.4829) (xy 89.952322 -104.4829) (xy 89.952322 -104.8639) (xy 89.727278 -104.8639)
				)
			)
		)
	)
	(footprint ""
		(layer "F.Cu")
		(at 13.589 -41.91)
		(property "Reference" "R383"
			(at 0 1.17475 0)
			(unlocked yes)
			(layer "F.SilkS")
			(effects
				(font
					(size 0.635 0.4064)
					(thickness 0.1524)
				)
			)
		)
		(property "Value" "VAL*"
			(at 0.02032 2.13233 0)
			(unlocked yes)
			(layer "F.Fab")
			(hide yes)
			(effects
				(font
					(size 0.7874 0.5842)
					(thickness 0.1524)
				)
			)
		)
		(property "Tolerance" "TOL*"
			(at 0.044704 3.05435 0)
			(unlocked yes)
			(layer "Cmts.User")
			(hide yes)
			(effects
				(font
					(size 0.7874 0.5842)
					(thickness 0.1524)
				)
			)
		)
		(property "User Part Number" "PARTNUM*"
			(at 0.02032 4.024884 0)
			(unlocked yes)
			(layer "Cmts.User")
			(hide yes)
			(effects
				(font
					(size 0.7874 0.5842)
					(thickness 0.1524)
				)
			)
		)
		(property "Device Type" "RESISTOR-G155-14701-01,4.7KOHMA"
			(at 0.008382 1.210564 0)
			(unlocked yes)
			(layer "F.Fab")
			(hide yes)
			(effects
				(font
					(size 0.7874 0.5842)
					(thickness 0.1524)
				)
			)
		)
		(duplicate_pad_numbers_are_jumpers no)
		(fp_line
			(start -1.143 -0.5588)
			(end -1.143 0.5588)
			(stroke
				(width 0.1)
				(type default)
			)
			(layer "F.SilkS")
		)
		(fp_line
			(start -1.143 0.5588)
			(end 1.143 0.5588)
			(stroke
				(width 0.1)
				(type default)
			)
			(layer "F.SilkS")
		)
		(fp_line
			(start 1.143 -0.5588)
			(end -1.143 -0.5588)
			(stroke
				(width 0.1)
				(type default)
			)
			(layer "F.SilkS")
		)
		(fp_line
			(start 1.143 0.5588)
			(end 1.143 -0.5588)
			(stroke
				(width 0.1)
				(type default)
			)
			(layer "F.SilkS")
		)
		(fp_rect
			(start 1.143 0.5588)
			(end -1.143 -0.5588)
			(stroke
				(width 0)
				(type default)
			)
			(fill no)
			(layer "F.CrtYd")
		)
		(fp_line
			(start -0.508 -0.3048)
			(end -0.508 0.3048)
			(stroke
				(width 0.1)
				(type default)
			)
			(layer "F.Fab")
		)
		(fp_line
			(start -0.508 0.3048)
			(end 0.508 0.3048)
			(stroke
				(width 0.1)
				(type default)
			)
			(layer "F.Fab")
		)
		(fp_line
			(start 0.508 -0.3048)
			(end -0.508 -0.3048)
			(stroke
				(width 0.1)
				(type default)
			)
			(layer "F.Fab")
		)
		(fp_line
			(start 0.508 0.3048)
			(end 0.508 -0.3048)
			(stroke
				(width 0.1)
				(type default)
			)
			(layer "F.Fab")
		)
		(pad "1" smd rect
			(at -0.5334 0)
			(size 0.7112 0.6096)
			(layers "F.Cu" "F.Mask" "F.Paste")
			(net "XP3R3V_FPGA")
		)
		(pad "2" smd rect
			(at 0.5334 0)
			(size 0.7112 0.6096)
			(layers "F.Cu" "F.Mask" "F.Paste")
			(net "SMA2_SIG_IN_BF_EN_N")
		)
		(zone
			(layer "F.Cu")
			(hatch none 0.5)
			(connect_pads
				(clearance 0)
			)
			(min_thickness 0.25)
			(keepout
				(tracks not_allowed)
				(vias allowed)
				(pads allowed)
				(copperpour not_allowed)
				(footprints allowed)
			)
			(placement
				(enabled no)
				(sheetname "")
			)
			(fill
				(thermal_gap 0.5)
				(thermal_bridge_width 0.5)
				(island_removal_mode 0)
			)
			(polygon
				(pts
					(xy 13.6652 -41.6052) (xy 13.6652 -42.2148) (xy 13.5128 -42.2148) (xy 13.5128 -41.6052)
				)
			)
		)
		(zone
			(layer "F.Cu")
			(hatch none 0.5)
			(connect_pads
				(clearance 0)
			)
			(min_thickness 0.25)
			(keepout
				(tracks allowed)
				(vias not_allowed)
				(pads allowed)
				(copperpour not_allowed)
				(footprints allowed)
			)
			(placement
				(enabled no)
				(sheetname "")
			)
			(fill
				(thermal_gap 0.5)
				(thermal_bridge_width 0.5)
				(island_removal_mode 0)
			)
			(polygon
				(pts
					(xy 13.6652 -41.6052) (xy 13.6652 -42.2148) (xy 13.5128 -42.2148) (xy 13.5128 -41.6052)
				)
			)
		)
	)
)
